(kicad_pcb
	(version 20241229)
	(generator "pcbnew")
	(generator_version "9.0")
	(general
		(thickness 1.61)
		(legacy_teardrops no)
	)
	(paper "A3")
	(title_block
		(title "RDIMM DDR5 Tester")
		(date "2026-05-21")
		(rev "2.2.0")
		(company "Antmicro")
		(comment 9 "footprints 735-739 of 796")
	)
	(layers
		(0 "F.Cu" signal)
		(4 "In1.Cu" power)
		(6 "In2.Cu" mixed)
		(8 "In3.Cu" power)
		(10 "In4.Cu" mixed)
		(12 "In5.Cu" power)
		(14 "In6.Cu" mixed)
		(16 "In7.Cu" power)
		(18 "In8.Cu" power)
		(20 "In9.Cu" mixed)
		(22 "In10.Cu" power)
		(2 "B.Cu" signal)
		(9 "F.Adhes" user "F.Adhesive")
		(11 "B.Adhes" user "B.Adhesive")
		(13 "F.Paste" user)
		(15 "B.Paste" user)
		(5 "F.SilkS" user "F.Silkscreen")
		(7 "B.SilkS" user "B.Silkscreen")
		(1 "F.Mask" user)
		(3 "B.Mask" user)
		(17 "Dwgs.User" user "User.Drawings")
		(19 "Cmts.User" user "User.Comments")
		(21 "Eco1.User" user "User.Eco1")
		(23 "Eco2.User" user "User.Eco2")
		(25 "Edge.Cuts" user)
		(27 "Margin" user)
		(31 "F.CrtYd" user "F.Courtyard")
		(29 "B.CrtYd" user "B.Courtyard")
		(35 "F.Fab" user)
		(33 "B.Fab" user)
	)
	(footprint "antmicro-footprints:C_0402_1005Metric"
		(layer "B.Cu")
		(at 122.95 147.61)
		(descr "Capacitor SMD 0402")
		(tags "capacitor SMD 0402")
		(property "Reference" "C303"
			(at 2.32 0.932 0)
			(layer "B.SilkS")
			(effects
				(font
					(size 0.7 0.7)
					(thickness 0.15)
				)
				(justify right bottom mirror)
			)
		)
		(property "Value" "C_100n_0402"
			(at -1.022927 -2.155213 0)
			(layer "B.Fab")
			(effects
				(font
					(size 0.7 0.7)
					(thickness 0.15)
				)
				(justify right bottom mirror)
			)
		)
		(property "Datasheet" "https://www.murata.com/products/productdetail?partno=GRM155R61H104KE14%23"
			(at 0 0 0)
			(layer "F.Fab")
			(hide yes)
			(effects
				(font
					(size 1.27 1.27)
					(thickness 0.15)
				)
			)
		)
		(property "Manufacturer" "Murata"
			(at 0 0 0)
			(unlocked yes)
			(layer "B.Fab")
			(hide yes)
			(effects
				(font
					(size 1 1)
					(thickness 0.15)
				)
				(justify mirror)
			)
		)
		(property "MPN" "GRM155R61H104KE14D"
			(at 0 0 0)
			(unlocked yes)
			(layer "B.Fab")
			(hide yes)
			(effects
				(font
					(size 1 1)
					(thickness 0.15)
				)
				(justify mirror)
			)
		)
		(property "Val" "100n"
			(at 0 0 0)
			(unlocked yes)
			(layer "B.Fab")
			(hide yes)
			(effects
				(font
					(size 1 1)
					(thickness 0.15)
				)
				(justify mirror)
			)
		)
		(property "License" "Apache-2.0"
			(at 0 0 0)
			(unlocked yes)
			(layer "B.Fab")
			(hide yes)
			(effects
				(font
					(size 1 1)
					(thickness 0.15)
				)
				(justify mirror)
			)
		)
		(property "Author" "Antmicro"
			(at 0 0 0)
			(unlocked yes)
			(layer "B.Fab")
			(hide yes)
			(effects
				(font
					(size 1 1)
					(thickness 0.15)
				)
				(justify mirror)
			)
		)
		(property "Voltage" "50V"
			(at 0 0 0)
			(unlocked yes)
			(layer "B.Fab")
			(hide yes)
			(effects
				(font
					(size 1 1)
					(thickness 0.15)
				)
				(justify mirror)
			)
		)
		(property "Dielectric" "X5R"
			(at 0 0 0)
			(unlocked yes)
			(layer "B.Fab")
			(hide yes)
			(effects
				(font
					(size 1 1)
					(thickness 0.15)
				)
				(justify mirror)
			)
		)
		(sheetname "/FPGA MGT Interface/")
		(sheetfile "fpga-mgt.kicad_sch")
		(attr smd)
		(fp_rect
			(start -0.925 0.47)
			(end 0.925 -0.47)
			(stroke
				(width 0.05)
				(type default)
			)
			(fill no)
			(layer "B.CrtYd")
		)
		(fp_line
			(start -0.494 -0.248)
			(end -0.494 0.25)
			(stroke
				(width 0.15)
				(type solid)
			)
			(layer "B.Fab")
		)
		(fp_line
			(start -0.494 0.25)
			(end 0.504 0.25)
			(stroke
				(width 0.15)
				(type solid)
			)
			(layer "B.Fab")
		)
		(fp_line
			(start 0.504 -0.248)
			(end -0.494 -0.248)
			(stroke
				(width 0.15)
				(type solid)
			)
			(layer "B.Fab")
		)
		(fp_line
			(start 0.504 0.25)
			(end 0.504 -0.248)
			(stroke
				(width 0.15)
				(type solid)
			)
			(layer "B.Fab")
		)
		(fp_text user "Author: Antmicro"
			(at -0.939 -3.399 180)
			(layer "B.Fab")
			(effects
				(font
					(size 0.7 0.7)
					(thickness 0.15)
				)
				(justify left bottom mirror)
			)
		)
		(fp_text user "${REFERENCE}"
			(at -0.939 -4.599 180)
			(layer "B.Fab")
			(effects
				(font
					(size 0.7 0.7)
					(thickness 0.15)
				)
				(justify left bottom mirror)
			)
		)
		(fp_text user "License: Apache-2.0"
			(at -0.939 -5.799 180)
			(layer "B.Fab")
			(effects
				(font
					(size 0.7 0.7)
					(thickness 0.15)
				)
				(justify left bottom mirror)
			)
		)
		(pad "1" smd roundrect
			(at -0.48 0)
			(size 0.59 0.64)
			(layers "B.Cu" "B.Mask" "B.Paste")
			(roundrect_rratio 0.25)
			(net 344 "/FPGA MGT Interface/HDMI_IN.D2_P")
			(pintype "passive")
		)
		(pad "2" smd roundrect
			(at 0.48 0)
			(size 0.59 0.64)
			(layers "B.Cu" "B.Mask" "B.Paste")
			(roundrect_rratio 0.25)
			(net 649 "/FPGA MGT Interface/HDMI_FPGA.RX2_P")
			(pintype "passive")
		)
	)
	(footprint "antmicro-footprints:C_0402_1005Metric_EIA"
		(layer "B.Cu")
		(at 190 146.5 -90)
		(descr "Capacitor SMD 0402 (1005 Metric), square (rectangular) end terminal, IPC_7351 nominal, (Body size source: IPC-SM-782 page 76, https://www.pcb-3d.com/wordpress/wp-content/uploads/ipc-sm-782a_amendment_1_and_2.pdf)")
		(tags "capacitor 0402")
		(property "Reference" "C68"
			(at -12.15 30.65 90)
			(layer "B.SilkS")
			(effects
				(font
					(size 0.7 0.7)
					(thickness 0.15)
				)
				(justify left bottom mirror)
			)
		)
		(property "Value" "C_100n_0402"
			(at 0 -1.169 90)
			(layer "B.Fab")
			(effects
				(font
					(size 0.7 0.7)
					(thickness 0.15)
				)
				(justify left bottom mirror)
			)
		)
		(property "Datasheet" "https://www.murata.com/products/productdetail?partno=GRM155R61H104KE14%23"
			(at 0 0 270)
			(layer "F.Fab")
			(hide yes)
			(effects
				(font
					(size 1.27 1.27)
					(thickness 0.15)
				)
			)
		)
		(property "MPN" "GRM155R61H104KE14D"
			(at 0 0 270)
			(unlocked yes)
			(layer "B.Fab")
			(hide yes)
			(effects
				(font
					(size 1 1)
					(thickness 0.15)
				)
				(justify mirror)
			)
		)
		(property "Manufacturer" "Murata"
			(at 0 0 270)
			(unlocked yes)
			(layer "B.Fab")
			(hide yes)
			(effects
				(font
					(size 1 1)
					(thickness 0.15)
				)
				(justify mirror)
			)
		)
		(property "License" "Apache-2.0"
			(at 0 0 270)
			(unlocked yes)
			(layer "B.Fab")
			(hide yes)
			(effects
				(font
					(size 1 1)
					(thickness 0.15)
				)
				(justify mirror)
			)
		)
		(property "Author" "Antmicro"
			(at 0 0 270)
			(unlocked yes)
			(layer "B.Fab")
			(hide yes)
			(effects
				(font
					(size 1 1)
					(thickness 0.15)
				)
				(justify mirror)
			)
		)
		(property "Val" "100n"
			(at 0 0 270)
			(unlocked yes)
			(layer "B.Fab")
			(hide yes)
			(effects
				(font
					(size 1 1)
					(thickness 0.15)
				)
				(justify mirror)
			)
		)
		(property "Voltage" "50V"
			(at 0 0 270)
			(unlocked yes)
			(layer "B.Fab")
			(hide yes)
			(effects
				(font
					(size 1 1)
					(thickness 0.15)
				)
				(justify mirror)
			)
		)
		(property "Dielectric" "X5R"
			(at 0 0 270)
			(unlocked yes)
			(layer "B.Fab")
			(hide yes)
			(effects
				(font
					(size 1 1)
					(thickness 0.15)
				)
				(justify mirror)
			)
		)
		(sheetname "/FPGA power/")
		(sheetfile "fpga-power.kicad_sch")
		(attr smd)
		(fp_rect
			(start -0.95 0.45)
			(end 0.95 -0.45)
			(stroke
				(width 0.05)
				(type default)
			)
			(fill no)
			(layer "B.CrtYd")
		)
		(fp_line
			(start -0.5 0.25)
			(end 0.498 0.25)
			(stroke
				(width 0.15)
				(type solid)
			)
			(layer "B.Fab")
		)
		(fp_line
			(start 0.498 0.25)
			(end 0.498 -0.248)
			(stroke
				(width 0.15)
				(type solid)
			)
			(layer "B.Fab")
		)
		(fp_line
			(start -0.5 -0.248)
			(end -0.5 0.25)
			(stroke
				(width 0.15)
				(type solid)
			)
			(layer "B.Fab")
		)
		(fp_line
			(start 0.498 -0.248)
			(end -0.5 -0.248)
			(stroke
				(width 0.15)
				(type solid)
			)
			(layer "B.Fab")
		)
		(fp_text user "License: Apache-2.0"
			(at -0.9656 -4.369 90)
			(layer "B.Fab")
			(effects
				(font
					(size 0.7 0.7)
					(thickness 0.15)
				)
				(justify left bottom mirror)
			)
		)
		(fp_text user "Author: Antmicro"
			(at -0.9656 -5.569 90)
			(layer "B.Fab")
			(effects
				(font
					(size 0.7 0.7)
					(thickness 0.15)
				)
				(justify left bottom mirror)
			)
		)
		(fp_text user "${REFERENCE}"
			(at -0.9656 -3.169 90)
			(layer "B.Fab")
			(effects
				(font
					(size 0.7 0.7)
					(thickness 0.15)
				)
				(justify left bottom mirror)
			)
		)
		(pad "1" smd roundrect
			(at -0.5 0 180)
			(size 0.6 0.6)
			(layers "B.Cu" "B.Mask" "B.Paste")
			(roundrect_rratio 0.25)
			(net 1 "GND")
			(pintype "passive")
		)
		(pad "2" smd roundrect
			(at 0.498 0 270)
			(size 0.6 0.6)
			(layers "B.Cu" "B.Mask" "B.Paste")
			(roundrect_rratio 0.25)
			(net 797 "+1V8")
			(pintype "passive")
		)
	)
	(footprint "antmicro-footprints:R_0402_1005Metric"
		(layer "B.Cu")
		(at 196.5 136.8 90)
		(descr "Resistor SMD 0402")
		(tags "resistor SMD 0402")
		(property "Reference" "R257"
			(at 2.3 0 270)
			(layer "B.SilkS")
			(effects
				(font
					(size 0.7 0.7)
					(thickness 0.15)
				)
				(justify mirror)
			)
		)
		(property "Value" "R_0R_0402"
			(at -1.011843 -1.772047 270)
			(layer "B.Fab")
			(effects
				(font
					(size 0.7 0.7)
					(thickness 0.15)
				)
				(justify left bottom mirror)
			)
		)
		(property "Datasheet" "https://industrial.panasonic.com/cdbs/www-data/pdf/RDA0000/AOA0000C301.pdf"
			(at 0 0 270)
			(layer "B.Fab")
			(hide yes)
			(effects
				(font
					(size 1.27 1.27)
					(thickness 0.15)
				)
				(justify mirror)
			)
		)
		(property "MPN" "ERJ2GE0R00X"
			(at 0 0 90)
			(unlocked yes)
			(layer "B.Fab")
			(hide yes)
			(effects
				(font
					(size 1 1)
					(thickness 0.15)
				)
				(justify mirror)
			)
		)
		(property "Manufacturer" "Panasonic"
			(at 0 0 90)
			(unlocked yes)
			(layer "B.Fab")
			(hide yes)
			(effects
				(font
					(size 1 1)
					(thickness 0.15)
				)
				(justify mirror)
			)
		)
		(property "License" "Apache-2.0"
			(at 0 0 90)
			(unlocked yes)
			(layer "B.Fab")
			(hide yes)
			(effects
				(font
					(size 1 1)
					(thickness 0.15)
				)
				(justify mirror)
			)
		)
		(property "Author" "Antmicro"
			(at 0 0 90)
			(unlocked yes)
			(layer "B.Fab")
			(hide yes)
			(effects
				(font
					(size 1 1)
					(thickness 0.15)
				)
				(justify mirror)
			)
		)
		(property "Val" "0R"
			(at 0 0 90)
			(unlocked yes)
			(layer "B.Fab")
			(hide yes)
			(effects
				(font
					(size 1 1)
					(thickness 0.15)
				)
				(justify mirror)
			)
		)
		(property "Tolerance" "~"
			(at 0 0 90)
			(unlocked yes)
			(layer "B.Fab")
			(hide yes)
			(effects
				(font
					(size 1 1)
					(thickness 0.15)
				)
				(justify mirror)
			)
		)
		(property "Current" "1A"
			(at 0 0 90)
			(unlocked yes)
			(layer "B.Fab")
			(hide yes)
			(effects
				(font
					(size 1 1)
					(thickness 0.15)
				)
				(justify mirror)
			)
		)
		(sheetname "/FPGA banks HP/")
		(sheetfile "fpga-hp-banks.kicad_sch")
		(attr smd)
		(fp_rect
			(start -0.925 0.47)
			(end 0.925 -0.47)
			(stroke
				(width 0.05)
				(type default)
			)
			(fill no)
			(layer "B.CrtYd")
		)
		(fp_rect
			(start -0.5 0.25)
			(end 0.5 -0.25)
			(stroke
				(width 0.15)
				(type solid)
			)
			(fill no)
			(layer "B.Fab")
		)
		(fp_text user "License: Apache-2.0"
			(at -0.95 -5.169 270)
			(layer "B.Fab")
			(effects
				(font
					(size 0.7 0.7)
					(thickness 0.15)
				)
				(justify left bottom mirror)
			)
		)
		(fp_text user "Author: Antmicro"
			(at -0.95 -4.169 270)
			(layer "B.Fab")
			(effects
				(font
					(size 0.7 0.7)
					(thickness 0.15)
				)
				(justify left bottom mirror)
			)
		)
		(fp_text user "${REFERENCE}"
			(at -0.95 -3.168 270)
			(layer "B.Fab")
			(effects
				(font
					(size 0.7 0.7)
					(thickness 0.15)
				)
				(justify left bottom mirror)
			)
		)
		(pad "1" smd roundrect
			(at -0.48 0 90)
			(size 0.59 0.64)
			(layers "B.Cu" "B.Mask" "B.Paste")
			(roundrect_rratio 0.25)
			(net 535 "/FPGA banks HP/VREF_64")
			(pintype "passive")
		)
		(pad "2" smd roundrect
			(at 0.48 0 90)
			(size 0.59 0.64)
			(layers "B.Cu" "B.Mask" "B.Paste")
			(roundrect_rratio 0.25)
			(net 826 "/FPGA banks HP/VREF")
			(pintype "passive")
		)
	)
	(footprint "antmicro-footprints:C_0402_1005Metric_EIA"
		(layer "B.Cu")
		(at 183 144.5 90)
		(descr "Capacitor SMD 0402 (1005 Metric), square (rectangular) end terminal, IPC_7351 nominal, (Body size source: IPC-SM-782 page 76, https://www.pcb-3d.com/wordpress/wp-content/uploads/ipc-sm-782a_amendment_1_and_2.pdf)")
		(tags "capacitor 0402")
		(property "Reference" "C78"
			(at -1.05 1.475 90)
			(layer "B.SilkS")
			(effects
				(font
					(size 0.7 0.7)
					(thickness 0.15)
				)
				(justify right bottom mirror)
			)
		)
		(property "Value" "C_100n_0402"
			(at 0 -1.169 90)
			(layer "B.Fab")
			(effects
				(font
					(size 0.7 0.7)
					(thickness 0.15)
				)
				(justify right bottom mirror)
			)
		)
		(property "Datasheet" "https://www.murata.com/products/productdetail?partno=GRM155R61H104KE14%23"
			(at 0 0 90)
			(layer "F.Fab")
			(hide yes)
			(effects
				(font
					(size 1.27 1.27)
					(thickness 0.15)
				)
			)
		)
		(property "MPN" "GRM155R61H104KE14D"
			(at 0 0 90)
			(unlocked yes)
			(layer "B.Fab")
			(hide yes)
			(effects
				(font
					(size 1 1)
					(thickness 0.15)
				)
				(justify mirror)
			)
		)
		(property "Manufacturer" "Murata"
			(at 0 0 90)
			(unlocked yes)
			(layer "B.Fab")
			(hide yes)
			(effects
				(font
					(size 1 1)
					(thickness 0.15)
				)
				(justify mirror)
			)
		)
		(property "License" "Apache-2.0"
			(at 0 0 90)
			(unlocked yes)
			(layer "B.Fab")
			(hide yes)
			(effects
				(font
					(size 1 1)
					(thickness 0.15)
				)
				(justify mirror)
			)
		)
		(property "Author" "Antmicro"
			(at 0 0 90)
			(unlocked yes)
			(layer "B.Fab")
			(hide yes)
			(effects
				(font
					(size 1 1)
					(thickness 0.15)
				)
				(justify mirror)
			)
		)
		(property "Val" "100n"
			(at 0 0 90)
			(unlocked yes)
			(layer "B.Fab")
			(hide yes)
			(effects
				(font
					(size 1 1)
					(thickness 0.15)
				)
				(justify mirror)
			)
		)
		(property "Voltage" "50V"
			(at 0 0 90)
			(unlocked yes)
			(layer "B.Fab")
			(hide yes)
			(effects
				(font
					(size 1 1)
					(thickness 0.15)
				)
				(justify mirror)
			)
		)
		(property "Dielectric" "X5R"
			(at 0 0 90)
			(unlocked yes)
			(layer "B.Fab")
			(hide yes)
			(effects
				(font
					(size 1 1)
					(thickness 0.15)
				)
				(justify mirror)
			)
		)
		(sheetname "/FPGA power/")
		(sheetfile "fpga-power.kicad_sch")
		(attr smd)
		(fp_rect
			(start -0.95 0.45)
			(end 0.95 -0.45)
			(stroke
				(width 0.05)
				(type default)
			)
			(fill no)
			(layer "B.CrtYd")
		)
		(fp_line
			(start 0.498 -0.248)
			(end -0.5 -0.248)
			(stroke
				(width 0.15)
				(type solid)
			)
			(layer "B.Fab")
		)
		(fp_line
			(start -0.5 -0.248)
			(end -0.5 0.25)
			(stroke
				(width 0.15)
				(type solid)
			)
			(layer "B.Fab")
		)
		(fp_line
			(start 0.498 0.25)
			(end 0.498 -0.248)
			(stroke
				(width 0.15)
				(type solid)
			)
			(layer "B.Fab")
		)
		(fp_line
			(start -0.5 0.25)
			(end 0.498 0.25)
			(stroke
				(width 0.15)
				(type solid)
			)
			(layer "B.Fab")
		)
		(fp_text user "Author: Antmicro"
			(at -0.9656 -5.569 270)
			(layer "B.Fab")
			(effects
				(font
					(size 0.7 0.7)
					(thickness 0.15)
				)
				(justify left bottom mirror)
			)
		)
		(fp_text user "${REFERENCE}"
			(at -0.9656 -3.169 270)
			(layer "B.Fab")
			(effects
				(font
					(size 0.7 0.7)
					(thickness 0.15)
				)
				(justify left bottom mirror)
			)
		)
		(fp_text user "License: Apache-2.0"
			(at -0.9656 -4.369 270)
			(layer "B.Fab")
			(effects
				(font
					(size 0.7 0.7)
					(thickness 0.15)
				)
				(justify left bottom mirror)
			)
		)
		(pad "1" smd roundrect
			(at -0.5 0)
			(size 0.6 0.6)
			(layers "B.Cu" "B.Mask" "B.Paste")
			(roundrect_rratio 0.25)
			(net 1 "GND")
			(pintype "passive")
		)
		(pad "2" smd roundrect
			(at 0.498 0 90)
			(size 0.6 0.6)
			(layers "B.Cu" "B.Mask" "B.Paste")
			(roundrect_rratio 0.25)
			(net 687 "VDDQ")
			(pintype "passive")
		)
	)
	(footprint "antmicro-footprints:C_0402_1005Metric"
		(layer "B.Cu")
		(at 190.672499 193.2285 90)
		(descr "Capacitor SMD 0402")
		(tags "capacitor SMD 0402")
		(property "Reference" "C254"
			(at 0.994 0.403501 90)
			(layer "B.SilkS")
			(effects
				(font
					(size 0.7 0.7)
					(thickness 0.15)
				)
				(justify right bottom mirror)
			)
		)
		(property "Value" "C_100n_0402"
			(at -1.022927 -2.155213 90)
			(layer "B.Fab")
			(effects
				(font
					(size 0.7 0.7)
					(thickness 0.15)
				)
				(justify right bottom mirror)
			)
		)
		(property "Datasheet" "https://www.murata.com/products/productdetail?partno=GRM155R61H104KE14%23"
			(at 0 0 90)
			(layer "F.Fab")
			(hide yes)
			(effects
				(font
					(size 1.27 1.27)
					(thickness 0.15)
				)
			)
		)
		(property "Manufacturer" "Murata"
			(at 0 0 90)
			(unlocked yes)
			(layer "B.Fab")
			(hide yes)
			(effects
				(font
					(size 1 1)
					(thickness 0.15)
				)
				(justify mirror)
			)
		)
		(property "MPN" "GRM155R61H104KE14D"
			(at 0 0 90)
			(unlocked yes)
			(layer "B.Fab")
			(hide yes)
			(effects
				(font
					(size 1 1)
					(thickness 0.15)
				)
				(justify mirror)
			)
		)
		(property "Val" "100n"
			(at 0 0 90)
			(unlocked yes)
			(layer "B.Fab")
			(hide yes)
			(effects
				(font
					(size 1 1)
					(thickness 0.15)
				)
				(justify mirror)
			)
		)
		(property "License" "Apache-2.0"
			(at 0 0 90)
			(unlocked yes)
			(layer "B.Fab")
			(hide yes)
			(effects
				(font
					(size 1 1)
					(thickness 0.15)
				)
				(justify mirror)
			)
		)
		(property "Author" "Antmicro"
			(at 0 0 90)
			(unlocked yes)
			(layer "B.Fab")
			(hide yes)
			(effects
				(font
					(size 1 1)
					(thickness 0.15)
				)
				(justify mirror)
			)
		)
		(property "Voltage" "50V"
			(at 0 0 90)
			(unlocked yes)
			(layer "B.Fab")
			(hide yes)
			(effects
				(font
					(size 1 1)
					(thickness 0.15)
				)
				(justify mirror)
			)
		)
		(property "Dielectric" "X5R"
			(at 0 0 90)
			(unlocked yes)
			(layer "B.Fab")
			(hide yes)
			(effects
				(font
					(size 1 1)
					(thickness 0.15)
				)
				(justify mirror)
			)
		)
		(sheetname "/FPGA MGT Interface/")
		(sheetfile "fpga-mgt.kicad_sch")
		(attr smd)
		(fp_rect
			(start -0.925 0.47)
			(end 0.925 -0.47)
			(stroke
				(width 0.05)
				(type default)
			)
			(fill no)
			(layer "B.CrtYd")
		)
		(fp_line
			(start 0.504 -0.248)
			(end -0.494 -0.248)
			(stroke
				(width 0.15)
				(type solid)
			)
			(layer "B.Fab")
		)
		(fp_line
			(start -0.494 -0.248)
			(end -0.494 0.25)
			(stroke
				(width 0.15)
				(type solid)
			)
			(layer "B.Fab")
		)
		(fp_line
			(start 0.504 0.25)
			(end 0.504 -0.248)
			(stroke
				(width 0.15)
				(type solid)
			)
			(layer "B.Fab")
		)
		(fp_line
			(start -0.494 0.25)
			(end 0.504 0.25)
			(stroke
				(width 0.15)
				(type solid)
			)
			(layer "B.Fab")
		)
		(fp_text user "License: Apache-2.0"
			(at -0.939 -5.799 270)
			(layer "B.Fab")
			(effects
				(font
					(size 0.7 0.7)
					(thickness 0.15)
				)
				(justify left bottom mirror)
			)
		)
		(fp_text user "Author: Antmicro"
			(at -0.939 -3.399 270)
			(layer "B.Fab")
			(effects
				(font
					(size 0.7 0.7)
					(thickness 0.15)
				)
				(justify left bottom mirror)
			)
		)
		(fp_text user "${REFERENCE}"
			(at -0.939 -4.599 270)
			(layer "B.Fab")
			(effects
				(font
					(size 0.7 0.7)
					(thickness 0.15)
				)
				(justify left bottom mirror)
			)
		)
		(pad "1" smd roundrect
			(at -0.48 0 90)
			(size 0.59 0.64)
			(layers "B.Cu" "B.Mask" "B.Paste")
			(roundrect_rratio 0.25)
			(net 256 "/FPGA MGT Interface/PCIE.TXD6_N")
			(pintype "passive")
		)
		(pad "2" smd roundrect
			(at 0.48 0 90)
			(size 0.59 0.64)
			(layers "B.Cu" "B.Mask" "B.Paste")
			(roundrect_rratio 0.25)
			(net 562 "/FPGA MGT Interface/GTY_224_TX1_N")
			(pintype "passive")
		)
	)
)
